# T6G (Grand Teton) — schematic netlist excerpt (pin names and nets, part order shuffled) for the footprints in the layout excerpt that follows; sources: Cadence DE-HDL packaged netlist, KiCad conversion of 04192023_DAF0TMB3IC0_F0TG_MB_C_brd_V02_OCP.brd

PR602  Q_RES  4.99K 1% EMPTY  pkg 0402LF  page 210 : A = PVDDCR_CPU0_P1_VINSEN ; B = GND
R1269  Q_RES  0 5% CHIP  pkg 0402LF  page 357 : A = P12V_E1S_0_ADC_ALERT_R ; B = E1S_0_P3V3_P12V_ADC_R_ALERT

(kicad_pcb
	(version 20260206)
	(generator "pcbnew")
	(generator_version "10.0")
	(general
		(thickness 1.6)
		(legacy_teardrops no)
	)
	(paper "A4")
	(title_block
		(title "04192023_DAF0TMB3IC0_F0TG_MB_C_brd_V02_OCP.brd")
		(comment 1 "Grand Teton / footprints 3018-3019 of 8354")
	)
	(layers
		(0 "F.Cu" signal "TOP")
		(4 "In1.Cu" signal "GND")
		(6 "In2.Cu" signal "IN1")
		(8 "In3.Cu" signal "GND1")
		(10 "In4.Cu" signal "IN2")
		(12 "In5.Cu" signal "GND2")
		(14 "In6.Cu" signal "IN3")
		(16 "In7.Cu" signal "GND3")
		(18 "In8.Cu" signal "VCC")
		(20 "In9.Cu" signal "VCC1")
		(22 "In10.Cu" signal "GND4")
		(24 "In11.Cu" signal "IN4")
		(26 "In12.Cu" signal "GND5")
		(28 "In13.Cu" signal "IN5")
		(30 "In14.Cu" signal "GND6")
		(32 "In15.Cu" signal "IN6")
		(34 "In16.Cu" signal "GND7")
		(2 "B.Cu" signal "BOTTOM")
		(9 "F.Adhes" user "F.Adhesive")
		(11 "B.Adhes" user "B.Adhesive")
		(13 "F.Paste" user "Package Geometry/Pastemask Top")
		(15 "B.Paste" user "Package Geometry/Pastemask Bottom")
		(5 "F.SilkS" user "Ref Des/Silkscreen Top")
		(7 "B.SilkS" user "Ref Des/Silkscreen Bottom")
		(1 "F.Mask" user "Board Geometry/Soldermask Top")
		(3 "B.Mask" user "Board Geometry/Soldermask Bottom")
		(17 "Dwgs.User" user "User.Drawings")
		(19 "Cmts.User" user "User.Comments")
		(21 "Eco1.User" user "User.Eco1")
		(23 "Eco2.User" user "User.Eco2")
		(25 "Edge.Cuts" user "Board Geometry/Outline")
		(27 "Margin" user)
		(31 "F.CrtYd" user "Package Geometry/Place Bound Top")
		(29 "B.CrtYd" user "Package Geometry/Place Bound Bottom")
		(35 "F.Fab" user "Ref Des/Assembly Top")
		(33 "B.Fab" user "Ref Des/Assembly Bottom")
	)
	(footprint ""
		(layer "F.Cu")
		(at 101.948234 -140.18641)
		(property "Reference" "PR602"
			(at 0 0 0)
			(layer "F.SilkS")
			(hide yes)
			(effects
				(font
					(size 1.27 1.27)
				)
			)
		)
		(property "Value" ""
			(at 0 0 0)
			(layer "F.Fab")
			(effects
				(font
					(size 1.27 1.27)
				)
			)
		)
		(duplicate_pad_numbers_are_jumpers no)
		(fp_line
			(start -0.7874 -0.4064)
			(end 0.7874 -0.4064)
			(stroke
				(width 0.1524)
				(type default)
			)
			(layer "F.SilkS")
		)
		(fp_line
			(start -0.7874 0.4064)
			(end -0.7874 -0.4064)
			(stroke
				(width 0.1524)
				(type default)
			)
			(layer "F.SilkS")
		)
		(fp_line
			(start 0.7874 -0.4064)
			(end 0.7874 0.4064)
			(stroke
				(width 0.1524)
				(type default)
			)
			(layer "F.SilkS")
		)
		(fp_line
			(start 0.7874 0.4064)
			(end -0.7874 0.4064)
			(stroke
				(width 0.1524)
				(type default)
			)
			(layer "F.SilkS")
		)
		(fp_line
			(start -0.67945 -0.305054)
			(end -0.12065 -0.305054)
			(stroke
				(width 0.1)
				(type default)
			)
			(layer "F.Fab")
		)
		(fp_line
			(start -0.67945 0.3048)
			(end -0.67945 -0.305054)
			(stroke
				(width 0.1)
				(type default)
			)
			(layer "F.Fab")
		)
		(fp_line
			(start -0.12065 -0.305054)
			(end -0.12065 -0.2794)
			(stroke
				(width 0.1)
				(type default)
			)
			(layer "F.Fab")
		)
		(fp_line
			(start -0.12065 -0.2794)
			(end 0.12065 -0.2794)
			(stroke
				(width 0.1)
				(type default)
			)
			(layer "F.Fab")
		)
		(fp_line
			(start -0.12065 0.2794)
			(end -0.12065 0.3048)
			(stroke
				(width 0.1)
				(type default)
			)
			(layer "F.Fab")
		)
		(fp_line
			(start -0.12065 0.3048)
			(end -0.67945 0.3048)
			(stroke
				(width 0.1)
				(type default)
			)
			(layer "F.Fab")
		)
		(fp_line
			(start 0.120396 0.2794)
			(end -0.12065 0.2794)
			(stroke
				(width 0.1)
				(type default)
			)
			(layer "F.Fab")
		)
		(fp_line
			(start 0.120396 0.3048)
			(end 0.120396 0.2794)
			(stroke
				(width 0.1)
				(type default)
			)
			(layer "F.Fab")
		)
		(fp_line
			(start 0.12065 -0.3048)
			(end 0.67945 -0.3048)
			(stroke
				(width 0.1)
				(type default)
			)
			(layer "F.Fab")
		)
		(fp_line
			(start 0.12065 -0.2794)
			(end 0.12065 -0.3048)
			(stroke
				(width 0.1)
				(type default)
			)
			(layer "F.Fab")
		)
		(fp_line
			(start 0.67945 -0.3048)
			(end 0.67945 0.3048)
			(stroke
				(width 0.1)
				(type default)
			)
			(layer "F.Fab")
		)
		(fp_line
			(start 0.67945 0.3048)
			(end 0.120396 0.3048)
			(stroke
				(width 0.1)
				(type default)
			)
			(layer "F.Fab")
		)
		(pad "1" smd circle
			(at -0.40005 0)
			(size 0 0)
			(layers "F.Cu" "F.Mask" "F.Paste")
			(net "PVDDCR_CPU0_P1_VINSEN")
		)
		(pad "2" smd circle
			(at 0.40005 0)
			(size 0 0)
			(layers "F.Cu" "F.Mask" "F.Paste")
			(net "GND")
		)
	)
	(footprint ""
		(layer "F.Cu")
		(at 321.107308 -101.37775 180)
		(property "Reference" "R1269"
			(at 0 0 180)
			(layer "F.SilkS")
			(hide yes)
			(effects
				(font
					(size 1.27 1.27)
				)
			)
		)
		(property "Value" ""
			(at 0 0 180)
			(layer "F.Fab")
			(effects
				(font
					(size 1.27 1.27)
				)
			)
		)
		(duplicate_pad_numbers_are_jumpers no)
		(fp_line
			(start 0.7874 0.4064)
			(end -0.7874 0.4064)
			(stroke
				(width 0.1524)
				(type default)
			)
			(layer "F.SilkS")
		)
		(fp_line
			(start 0.7874 -0.4064)
			(end 0.7874 0.4064)
			(stroke
				(width 0.1524)
				(type default)
			)
			(layer "F.SilkS")
		)
		(fp_line
			(start -0.7874 0.4064)
			(end -0.7874 -0.4064)
			(stroke
				(width 0.1524)
				(type default)
			)
			(layer "F.SilkS")
		)
		(fp_line
			(start -0.7874 -0.4064)
			(end 0.7874 -0.4064)
			(stroke
				(width 0.1524)
				(type default)
			)
			(layer "F.SilkS")
		)
		(fp_line
			(start 0.67945 0.3048)
			(end 0.120396 0.3048)
			(stroke
				(width 0.1)
				(type default)
			)
			(layer "F.Fab")
		)
		(fp_line
			(start 0.67945 -0.3048)
			(end 0.67945 0.3048)
			(stroke
				(width 0.1)
				(type default)
			)
			(layer "F.Fab")
		)
		(fp_line
			(start 0.12065 -0.2794)
			(end 0.12065 -0.3048)
			(stroke
				(width 0.1)
				(type default)
			)
			(layer "F.Fab")
		)
		(fp_line
			(start 0.12065 -0.3048)
			(end 0.67945 -0.3048)
			(stroke
				(width 0.1)
				(type default)
			)
			(layer "F.Fab")
		)
		(fp_line
			(start 0.120396 0.3048)
			(end 0.120396 0.2794)
			(stroke
				(width 0.1)
				(type default)
			)
			(layer "F.Fab")
		)
		(fp_line
			(start 0.120396 0.2794)
			(end -0.12065 0.2794)
			(stroke
				(width 0.1)
				(type default)
			)
			(layer "F.Fab")
		)
		(fp_line
			(start -0.12065 0.3048)
			(end -0.67945 0.3048)
			(stroke
				(width 0.1)
				(type default)
			)
			(layer "F.Fab")
		)
		(fp_line
			(start -0.12065 0.2794)
			(end -0.12065 0.3048)
			(stroke
				(width 0.1)
				(type default)
			)
			(layer "F.Fab")
		)
		(fp_line
			(start -0.12065 -0.2794)
			(end 0.12065 -0.2794)
			(stroke
				(width 0.1)
				(type default)
			)
			(layer "F.Fab")
		)
		(fp_line
			(start -0.12065 -0.305054)
			(end -0.12065 -0.2794)
			(stroke
				(width 0.1)
				(type default)
			)
			(layer "F.Fab")
		)
		(fp_line
			(start -0.67945 0.3048)
			(end -0.67945 -0.305054)
			(stroke
				(width 0.1)
				(type default)
			)
			(layer "F.Fab")
		)
		(fp_line
			(start -0.67945 -0.305054)
			(end -0.12065 -0.305054)
			(stroke
				(width 0.1)
				(type default)
			)
			(layer "F.Fab")
		)
		(pad "1" smd circle
			(at -0.40005 0 180)
			(size 0 0)
			(layers "F.Cu" "F.Mask" "F.Paste")
			(net "P12V_E1S_0_ADC_ALERT_R")
		)
		(pad "2" smd circle
			(at 0.40005 0 180)
			(size 0 0)
			(layers "F.Cu" "F.Mask" "F.Paste")
			(net "E1S_0_P3V3_P12V_ADC_R_ALERT")
		)
	)
)
